(kicad_pcb
	(version 20260206)
	(generator "pcbnew")
	(generator_version "10.0")
	(general
		(thickness 1.6)
		(legacy_teardrops no)
	)
	(paper "A4")
	(title_block
		(title "12092022_DA0F0TFB6D0_F0T_FAN_BOARD_MP5048_D_brd_v02_OCP.brd")
		(comment 1 "Grand Teton / footprints 560-565 of 924")
	)
	(layers
		(0 "F.Cu" signal "TOP")
		(4 "In1.Cu" signal "GND")
		(6 "In2.Cu" signal "IN1")
		(8 "In3.Cu" signal "IN2")
		(10 "In4.Cu" signal "GND1")
		(2 "B.Cu" signal "BOTTOM")
		(9 "F.Adhes" user "F.Adhesive")
		(11 "B.Adhes" user "B.Adhesive")
		(13 "F.Paste" user "Package Geometry/Pastemask Top")
		(15 "B.Paste" user "Package Geometry/Pastemask Bottom")
		(5 "F.SilkS" user "Ref Des/Silkscreen Top")
		(7 "B.SilkS" user "Ref Des/Silkscreen Bottom")
		(1 "F.Mask" user "Board Geometry/Soldermask Top")
		(3 "B.Mask" user "Board Geometry/Soldermask Bottom")
		(17 "Dwgs.User" user "User.Drawings")
		(19 "Cmts.User" user "User.Comments")
		(21 "Eco1.User" user "User.Eco1")
		(23 "Eco2.User" user "User.Eco2")
		(25 "Edge.Cuts" user "Board Geometry/Outline")
		(27 "Margin" user)
		(31 "F.CrtYd" user "Package Geometry/Place Bound Top")
		(29 "B.CrtYd" user "Package Geometry/Place Bound Bottom")
		(35 "F.Fab" user "Ref Des/Assembly Top")
		(33 "B.Fab" user "Ref Des/Assembly Bottom")
	)
	(footprint ""
		(layer "F.Cu")
		(at 25.527 -121.539 180)
		(property "Reference" "R5460"
			(at 0 0 180)
			(layer "F.SilkS")
			(hide yes)
			(effects
				(font
					(size 1.27 1.27)
				)
			)
		)
		(property "Value" ""
			(at 0 0 180)
			(layer "F.Fab")
			(effects
				(font
					(size 1.27 1.27)
				)
			)
		)
		(duplicate_pad_numbers_are_jumpers no)
		(fp_line
			(start 0.7874 0.4064)
			(end -0.7874 0.4064)
			(stroke
				(width 0.1524)
				(type default)
			)
			(layer "F.SilkS")
		)
		(fp_line
			(start 0.7874 -0.4064)
			(end 0.7874 0.4064)
			(stroke
				(width 0.1524)
				(type default)
			)
			(layer "F.SilkS")
		)
		(fp_line
			(start -0.7874 0.4064)
			(end -0.7874 -0.4064)
			(stroke
				(width 0.1524)
				(type default)
			)
			(layer "F.SilkS")
		)
		(fp_line
			(start -0.7874 -0.4064)
			(end 0.7874 -0.4064)
			(stroke
				(width 0.1524)
				(type default)
			)
			(layer "F.SilkS")
		)
		(fp_line
			(start 0.67945 0.3048)
			(end 0.120396 0.3048)
			(stroke
				(width 0.1)
				(type default)
			)
			(layer "F.Fab")
		)
		(fp_line
			(start 0.67945 -0.3048)
			(end 0.67945 0.3048)
			(stroke
				(width 0.1)
				(type default)
			)
			(layer "F.Fab")
		)
		(fp_line
			(start 0.12065 -0.2794)
			(end 0.12065 -0.3048)
			(stroke
				(width 0.1)
				(type default)
			)
			(layer "F.Fab")
		)
		(fp_line
			(start 0.12065 -0.3048)
			(end 0.67945 -0.3048)
			(stroke
				(width 0.1)
				(type default)
			)
			(layer "F.Fab")
		)
		(fp_line
			(start 0.120396 0.3048)
			(end 0.120396 0.2794)
			(stroke
				(width 0.1)
				(type default)
			)
			(layer "F.Fab")
		)
		(fp_line
			(start 0.120396 0.2794)
			(end -0.12065 0.2794)
			(stroke
				(width 0.1)
				(type default)
			)
			(layer "F.Fab")
		)
		(fp_line
			(start -0.12065 0.3048)
			(end -0.67945 0.3048)
			(stroke
				(width 0.1)
				(type default)
			)
			(layer "F.Fab")
		)
		(fp_line
			(start -0.12065 0.2794)
			(end -0.12065 0.3048)
			(stroke
				(width 0.1)
				(type default)
			)
			(layer "F.Fab")
		)
		(fp_line
			(start -0.12065 -0.2794)
			(end 0.12065 -0.2794)
			(stroke
				(width 0.1)
				(type default)
			)
			(layer "F.Fab")
		)
		(fp_line
			(start -0.12065 -0.305054)
			(end -0.12065 -0.2794)
			(stroke
				(width 0.1)
				(type default)
			)
			(layer "F.Fab")
		)
		(fp_line
			(start -0.67945 0.3048)
			(end -0.67945 -0.305054)
			(stroke
				(width 0.1)
				(type default)
			)
			(layer "F.Fab")
		)
		(fp_line
			(start -0.67945 -0.305054)
			(end -0.12065 -0.305054)
			(stroke
				(width 0.1)
				(type default)
			)
			(layer "F.Fab")
		)
		(pad "1" smd circle
			(at -0.40005 0 180)
			(size 0 0)
			(layers "F.Cu" "F.Mask" "F.Paste")
			(net "SMB_PDBV_FAN_SDA")
		)
		(pad "2" smd circle
			(at 0.40005 0 180)
			(size 0 0)
			(layers "F.Cu" "F.Mask" "F.Paste")
			(net "SMB_PDBV_FAN_R_U330_SDA")
		)
	)
	(footprint ""
		(layer "F.Cu")
		(at 14.351 -107.880912 180)
		(property "Reference" "R5203"
			(at 0 0 180)
			(layer "F.SilkS")
			(hide yes)
			(effects
				(font
					(size 1.27 1.27)
				)
			)
		)
		(property "Value" ""
			(at 0 0 180)
			(layer "F.Fab")
			(effects
				(font
					(size 1.27 1.27)
				)
			)
		)
		(duplicate_pad_numbers_are_jumpers no)
		(fp_line
			(start 0.7874 0.4064)
			(end -0.7874 0.4064)
			(stroke
				(width 0.1524)
				(type default)
			)
			(layer "F.SilkS")
		)
		(fp_line
			(start 0.7874 -0.4064)
			(end 0.7874 0.4064)
			(stroke
				(width 0.1524)
				(type default)
			)
			(layer "F.SilkS")
		)
		(fp_line
			(start -0.7874 0.4064)
			(end -0.7874 -0.4064)
			(stroke
				(width 0.1524)
				(type default)
			)
			(layer "F.SilkS")
		)
		(fp_line
			(start -0.7874 -0.4064)
			(end 0.7874 -0.4064)
			(stroke
				(width 0.1524)
				(type default)
			)
			(layer "F.SilkS")
		)
		(fp_line
			(start 0.67945 0.3048)
			(end 0.120396 0.3048)
			(stroke
				(width 0.1)
				(type default)
			)
			(layer "F.Fab")
		)
		(fp_line
			(start 0.67945 -0.3048)
			(end 0.67945 0.3048)
			(stroke
				(width 0.1)
				(type default)
			)
			(layer "F.Fab")
		)
		(fp_line
			(start 0.12065 -0.2794)
			(end 0.12065 -0.3048)
			(stroke
				(width 0.1)
				(type default)
			)
			(layer "F.Fab")
		)
		(fp_line
			(start 0.12065 -0.3048)
			(end 0.67945 -0.3048)
			(stroke
				(width 0.1)
				(type default)
			)
			(layer "F.Fab")
		)
		(fp_line
			(start 0.120396 0.3048)
			(end 0.120396 0.2794)
			(stroke
				(width 0.1)
				(type default)
			)
			(layer "F.Fab")
		)
		(fp_line
			(start 0.120396 0.2794)
			(end -0.12065 0.2794)
			(stroke
				(width 0.1)
				(type default)
			)
			(layer "F.Fab")
		)
		(fp_line
			(start -0.12065 0.3048)
			(end -0.67945 0.3048)
			(stroke
				(width 0.1)
				(type default)
			)
			(layer "F.Fab")
		)
		(fp_line
			(start -0.12065 0.2794)
			(end -0.12065 0.3048)
			(stroke
				(width 0.1)
				(type default)
			)
			(layer "F.Fab")
		)
		(fp_line
			(start -0.12065 -0.2794)
			(end 0.12065 -0.2794)
			(stroke
				(width 0.1)
				(type default)
			)
			(layer "F.Fab")
		)
		(fp_line
			(start -0.12065 -0.305054)
			(end -0.12065 -0.2794)
			(stroke
				(width 0.1)
				(type default)
			)
			(layer "F.Fab")
		)
		(fp_line
			(start -0.67945 0.3048)
			(end -0.67945 -0.305054)
			(stroke
				(width 0.1)
				(type default)
			)
			(layer "F.Fab")
		)
		(fp_line
			(start -0.67945 -0.305054)
			(end -0.12065 -0.305054)
			(stroke
				(width 0.1)
				(type default)
			)
			(layer "F.Fab")
		)
		(pad "1" smd circle
			(at -0.40005 0 180)
			(size 0 0)
			(layers "F.Cu" "F.Mask" "F.Paste")
			(net "SMB_FAN5_SCL")
		)
		(pad "2" smd circle
			(at 0.40005 0 180)
			(size 0 0)
			(layers "F.Cu" "F.Mask" "F.Paste")
			(net "SMB_FAN5_SCL_R")
		)
	)
	(footprint ""
		(layer "F.Cu")
		(at 46.101 -124.079 90)
		(property "Reference" "R5693"
			(at 0 0 90)
			(layer "F.SilkS")
			(hide yes)
			(effects
				(font
					(size 1.27 1.27)
				)
			)
		)
		(property "Value" ""
			(at 0 0 90)
			(layer "F.Fab")
			(effects
				(font
					(size 1.27 1.27)
				)
			)
		)
		(duplicate_pad_numbers_are_jumpers no)
		(fp_line
			(start 0.7874 -0.4064)
			(end 0.7874 0.4064)
			(stroke
				(width 0.1524)
				(type default)
			)
			(layer "F.SilkS")
		)
		(fp_line
			(start -0.7874 -0.4064)
			(end 0.7874 -0.4064)
			(stroke
				(width 0.1524)
				(type default)
			)
			(layer "F.SilkS")
		)
		(fp_line
			(start 0.7874 0.4064)
			(end -0.7874 0.4064)
			(stroke
				(width 0.1524)
				(type default)
			)
			(layer "F.SilkS")
		)
		(fp_line
			(start -0.7874 0.4064)
			(end -0.7874 -0.4064)
			(stroke
				(width 0.1524)
				(type default)
			)
			(layer "F.SilkS")
		)
		(fp_line
			(start -0.12065 -0.305054)
			(end -0.12065 -0.2794)
			(stroke
				(width 0.1)
				(type default)
			)
			(layer "F.Fab")
		)
		(fp_line
			(start -0.67945 -0.305054)
			(end -0.12065 -0.305054)
			(stroke
				(width 0.1)
				(type default)
			)
			(layer "F.Fab")
		)
		(fp_line
			(start 0.67945 -0.3048)
			(end 0.67945 0.3048)
			(stroke
				(width 0.1)
				(type default)
			)
			(layer "F.Fab")
		)
		(fp_line
			(start 0.12065 -0.3048)
			(end 0.67945 -0.3048)
			(stroke
				(width 0.1)
				(type default)
			)
			(layer "F.Fab")
		)
		(fp_line
			(start 0.12065 -0.2794)
			(end 0.12065 -0.3048)
			(stroke
				(width 0.1)
				(type default)
			)
			(layer "F.Fab")
		)
		(fp_line
			(start -0.12065 -0.2794)
			(end 0.12065 -0.2794)
			(stroke
				(width 0.1)
				(type default)
			)
			(layer "F.Fab")
		)
		(fp_line
			(start 0.120396 0.2794)
			(end -0.12065 0.2794)
			(stroke
				(width 0.1)
				(type default)
			)
			(layer "F.Fab")
		)
		(fp_line
			(start -0.12065 0.2794)
			(end -0.12065 0.3048)
			(stroke
				(width 0.1)
				(type default)
			)
			(layer "F.Fab")
		)
		(fp_line
			(start 0.67945 0.3048)
			(end 0.120396 0.3048)
			(stroke
				(width 0.1)
				(type default)
			)
			(layer "F.Fab")
		)
		(fp_line
			(start 0.120396 0.3048)
			(end 0.120396 0.2794)
			(stroke
				(width 0.1)
				(type default)
			)
			(layer "F.Fab")
		)
		(fp_line
			(start -0.12065 0.3048)
			(end -0.67945 0.3048)
			(stroke
				(width 0.1)
				(type default)
			)
			(layer "F.Fab")
		)
		(fp_line
			(start -0.67945 0.3048)
			(end -0.67945 -0.305054)
			(stroke
				(width 0.1)
				(type default)
			)
			(layer "F.Fab")
		)
		(pad "1" smd rect
			(at -0.40005 0 270)
			(size 0.4572 0.508)
			(layers "F.Cu" "F.Mask" "F.Paste")
			(net "P12V_LED_FAN2")
		)
		(pad "2" smd rect
			(at 0.40005 0 270)
			(size 0.4572 0.508)
			(layers "F.Cu" "F.Mask" "F.Paste")
			(net "P12V_LED_R_FAN2")
		)
	)
	(footprint ""
		(layer "F.Cu")
		(at 4.191 -174.244 180)
		(property "Reference" "R4867"
			(at 0 0 180)
			(layer "F.SilkS")
			(hide yes)
			(effects
				(font
					(size 1.27 1.27)
				)
			)
		)
		(property "Value" ""
			(at 0 0 180)
			(layer "F.Fab")
			(effects
				(font
					(size 1.27 1.27)
				)
			)
		)
		(duplicate_pad_numbers_are_jumpers no)
		(fp_line
			(start 0.7874 0.4064)
			(end -0.7874 0.4064)
			(stroke
				(width 0.1524)
				(type default)
			)
			(layer "F.SilkS")
		)
		(fp_line
			(start 0.7874 -0.4064)
			(end 0.7874 0.4064)
			(stroke
				(width 0.1524)
				(type default)
			)
			(layer "F.SilkS")
		)
		(fp_line
			(start -0.7874 0.4064)
			(end -0.7874 -0.4064)
			(stroke
				(width 0.1524)
				(type default)
			)
			(layer "F.SilkS")
		)
		(fp_line
			(start -0.7874 -0.4064)
			(end 0.7874 -0.4064)
			(stroke
				(width 0.1524)
				(type default)
			)
			(layer "F.SilkS")
		)
		(fp_line
			(start 0.67945 0.3048)
			(end 0.120396 0.3048)
			(stroke
				(width 0.1)
				(type default)
			)
			(layer "F.Fab")
		)
		(fp_line
			(start 0.67945 -0.3048)
			(end 0.67945 0.3048)
			(stroke
				(width 0.1)
				(type default)
			)
			(layer "F.Fab")
		)
		(fp_line
			(start 0.12065 -0.2794)
			(end 0.12065 -0.3048)
			(stroke
				(width 0.1)
				(type default)
			)
			(layer "F.Fab")
		)
		(fp_line
			(start 0.12065 -0.3048)
			(end 0.67945 -0.3048)
			(stroke
				(width 0.1)
				(type default)
			)
			(layer "F.Fab")
		)
		(fp_line
			(start 0.120396 0.3048)
			(end 0.120396 0.2794)
			(stroke
				(width 0.1)
				(type default)
			)
			(layer "F.Fab")
		)
		(fp_line
			(start 0.120396 0.2794)
			(end -0.12065 0.2794)
			(stroke
				(width 0.1)
				(type default)
			)
			(layer "F.Fab")
		)
		(fp_line
			(start -0.12065 0.3048)
			(end -0.67945 0.3048)
			(stroke
				(width 0.1)
				(type default)
			)
			(layer "F.Fab")
		)
		(fp_line
			(start -0.12065 0.2794)
			(end -0.12065 0.3048)
			(stroke
				(width 0.1)
				(type default)
			)
			(layer "F.Fab")
		)
		(fp_line
			(start -0.12065 -0.2794)
			(end 0.12065 -0.2794)
			(stroke
				(width 0.1)
				(type default)
			)
			(layer "F.Fab")
		)
		(fp_line
			(start -0.12065 -0.305054)
			(end -0.12065 -0.2794)
			(stroke
				(width 0.1)
				(type default)
			)
			(layer "F.Fab")
		)
		(fp_line
			(start -0.67945 0.3048)
			(end -0.67945 -0.305054)
			(stroke
				(width 0.1)
				(type default)
			)
			(layer "F.Fab")
		)
		(fp_line
			(start -0.67945 -0.305054)
			(end -0.12065 -0.305054)
			(stroke
				(width 0.1)
				(type default)
			)
			(layer "F.Fab")
		)
		(pad "1" smd circle
			(at -0.40005 0 180)
			(size 0 0)
			(layers "F.Cu" "F.Mask" "F.Paste")
			(net "FAN_7_PRSNT_BUF_R_N")
		)
		(pad "2" smd circle
			(at 0.40005 0 180)
			(size 0 0)
			(layers "F.Cu" "F.Mask" "F.Paste")
			(net "FAN_7_PRSNT_BUF_N")
		)
	)
	(footprint ""
		(layer "F.Cu")
		(at 15.113 -23.114 -90)
		(property "Reference" "R5358"
			(at 0 0 270)
			(layer "F.SilkS")
			(hide yes)
			(effects
				(font
					(size 1.27 1.27)
				)
			)
		)
		(property "Value" ""
			(at 0 0 270)
			(layer "F.Fab")
			(effects
				(font
					(size 1.27 1.27)
				)
			)
		)
		(duplicate_pad_numbers_are_jumpers no)
		(fp_line
			(start -0.7874 0.4064)
			(end -0.7874 -0.4064)
			(stroke
				(width 0.1524)
				(type default)
			)
			(layer "F.SilkS")
		)
		(fp_line
			(start 0.7874 0.4064)
			(end -0.7874 0.4064)
			(stroke
				(width 0.1524)
				(type default)
			)
			(layer "F.SilkS")
		)
		(fp_line
			(start -0.7874 -0.4064)
			(end 0.7874 -0.4064)
			(stroke
				(width 0.1524)
				(type default)
			)
			(layer "F.SilkS")
		)
		(fp_line
			(start 0.7874 -0.4064)
			(end 0.7874 0.4064)
			(stroke
				(width 0.1524)
				(type default)
			)
			(layer "F.SilkS")
		)
		(fp_line
			(start -0.67945 0.3048)
			(end -0.67945 -0.305054)
			(stroke
				(width 0.1)
				(type default)
			)
			(layer "F.Fab")
		)
		(fp_line
			(start -0.12065 0.3048)
			(end -0.67945 0.3048)
			(stroke
				(width 0.1)
				(type default)
			)
			(layer "F.Fab")
		)
		(fp_line
			(start 0.120396 0.3048)
			(end 0.120396 0.2794)
			(stroke
				(width 0.1)
				(type default)
			)
			(layer "F.Fab")
		)
		(fp_line
			(start 0.67945 0.3048)
			(end 0.120396 0.3048)
			(stroke
				(width 0.1)
				(type default)
			)
			(layer "F.Fab")
		)
		(fp_line
			(start -0.12065 0.2794)
			(end -0.12065 0.3048)
			(stroke
				(width 0.1)
				(type default)
			)
			(layer "F.Fab")
		)
		(fp_line
			(start 0.120396 0.2794)
			(end -0.12065 0.2794)
			(stroke
				(width 0.1)
				(type default)
			)
			(layer "F.Fab")
		)
		(fp_line
			(start -0.12065 -0.2794)
			(end 0.12065 -0.2794)
			(stroke
				(width 0.1)
				(type default)
			)
			(layer "F.Fab")
		)
		(fp_line
			(start 0.12065 -0.2794)
			(end 0.12065 -0.3048)
			(stroke
				(width 0.1)
				(type default)
			)
			(layer "F.Fab")
		)
		(fp_line
			(start 0.12065 -0.3048)
			(end 0.67945 -0.3048)
			(stroke
				(width 0.1)
				(type default)
			)
			(layer "F.Fab")
		)
		(fp_line
			(start 0.67945 -0.3048)
			(end 0.67945 0.3048)
			(stroke
				(width 0.1)
				(type default)
			)
			(layer "F.Fab")
		)
		(fp_line
			(start -0.67945 -0.305054)
			(end -0.12065 -0.305054)
			(stroke
				(width 0.1)
				(type default)
			)
			(layer "F.Fab")
		)
		(fp_line
			(start -0.12065 -0.305054)
			(end -0.12065 -0.2794)
			(stroke
				(width 0.1)
				(type default)
			)
			(layer "F.Fab")
		)
		(pad "1" smd rect
			(at -0.40005 0 90)
			(size 0.4572 0.508)
			(layers "F.Cu" "F.Mask" "F.Paste")
			(net "FAN_4_FAIL_LED_R_N")
		)
		(pad "2" smd rect
			(at 0.40005 0 90)
			(size 0.4572 0.508)
			(layers "F.Cu" "F.Mask" "F.Paste")
			(net "FAN_4_FAIL_R_LED_N")
		)
	)
	(footprint ""
		(layer "F.Cu")
		(at 44.667932 -255.905 -90)
		(property "Reference" "C2065"
			(at 0 0 270)
			(layer "F.SilkS")
			(hide yes)
			(effects
				(font
					(size 1.27 1.27)
				)
			)
		)
		(property "Value" ""
			(at 0 0 270)
			(layer "F.Fab")
			(effects
				(font
					(size 1.27 1.27)
				)
			)
		)
		(duplicate_pad_numbers_are_jumpers no)
		(fp_line
			(start -0.7874 0.4064)
			(end -0.7874 -0.4064)
			(stroke
				(width 0.1524)
				(type default)
			)
			(layer "F.SilkS")
		)
		(fp_line
			(start 0.7874 0.4064)
			(end -0.7874 0.4064)
			(stroke
				(width 0.1524)
				(type default)
			)
			(layer "F.SilkS")
		)
		(fp_line
			(start -0.7874 -0.4064)
			(end 0.7874 -0.4064)
			(stroke
				(width 0.1524)
				(type default)
			)
			(layer "F.SilkS")
		)
		(fp_line
			(start 0.7874 -0.4064)
			(end 0.7874 0.4064)
			(stroke
				(width 0.1524)
				(type default)
			)
			(layer "F.SilkS")
		)
		(fp_line
			(start -0.67945 0.3048)
			(end -0.67945 -0.305054)
			(stroke
				(width 0.1)
				(type default)
			)
			(layer "F.Fab")
		)
		(fp_line
			(start -0.12065 0.3048)
			(end -0.67945 0.3048)
			(stroke
				(width 0.1)
				(type default)
			)
			(layer "F.Fab")
		)
		(fp_line
			(start 0.120396 0.3048)
			(end 0.120396 0.2794)
			(stroke
				(width 0.1)
				(type default)
			)
			(layer "F.Fab")
		)
		(fp_line
			(start 0.67945 0.3048)
			(end 0.120396 0.3048)
			(stroke
				(width 0.1)
				(type default)
			)
			(layer "F.Fab")
		)
		(fp_line
			(start -0.12065 0.2794)
			(end -0.12065 0.3048)
			(stroke
				(width 0.1)
				(type default)
			)
			(layer "F.Fab")
		)
		(fp_line
			(start 0.120396 0.2794)
			(end -0.12065 0.2794)
			(stroke
				(width 0.1)
				(type default)
			)
			(layer "F.Fab")
		)
		(fp_line
			(start -0.12065 -0.2794)
			(end 0.12065 -0.2794)
			(stroke
				(width 0.1)
				(type default)
			)
			(layer "F.Fab")
		)
		(fp_line
			(start 0.12065 -0.2794)
			(end 0.12065 -0.3048)
			(stroke
				(width 0.1)
				(type default)
			)
			(layer "F.Fab")
		)
		(fp_line
			(start 0.12065 -0.3048)
			(end 0.67945 -0.3048)
			(stroke
				(width 0.1)
				(type default)
			)
			(layer "F.Fab")
		)
		(fp_line
			(start 0.67945 -0.3048)
			(end 0.67945 0.3048)
			(stroke
				(width 0.1)
				(type default)
			)
			(layer "F.Fab")
		)
		(fp_line
			(start -0.67945 -0.305054)
			(end -0.12065 -0.305054)
			(stroke
				(width 0.1)
				(type default)
			)
			(layer "F.Fab")
		)
		(fp_line
			(start -0.12065 -0.305054)
			(end -0.12065 -0.2794)
			(stroke
				(width 0.1)
				(type default)
			)
			(layer "F.Fab")
		)
		(pad "1" smd circle
			(at -0.40005 0 270)
			(size 0 0)
			(layers "F.Cu" "F.Mask" "F.Paste")
			(net "P3V3_AUX")
		)
		(pad "2" smd circle
			(at 0.40005 0 270)
			(size 0 0)
			(layers "F.Cu" "F.Mask" "F.Paste")
			(net "GND")
		)
	)
)
